(kicad_pcb
	(version 20260206)
	(generator "pcbnew")
	(generator_version "10.0")
	(general
		(thickness 1.6)
		(legacy_teardrops no)
	)
	(paper "A4")
	(title_block
		(title "01162023_DA0F0TEBIF0_F0T_Expander_BD_F_brd_V02_OCP.brd")
		(comment 1 "Grand Teton / footprints 4269-4273 of 9728")
	)
	(layers
		(0 "F.Cu" signal "TOP")
		(4 "In1.Cu" signal "GND")
		(6 "In2.Cu" signal "VCC")
		(8 "In3.Cu" signal "VCC1")
		(10 "In4.Cu" signal "GND1")
		(12 "In5.Cu" signal "IN1")
		(14 "In6.Cu" signal "GND2")
		(16 "In7.Cu" signal "IN2")
		(18 "In8.Cu" signal "GND3")
		(20 "In9.Cu" signal "IN3")
		(22 "In10.Cu" signal "GND4")
		(24 "In11.Cu" signal "IN4")
		(26 "In12.Cu" signal "GND5")
		(28 "In13.Cu" signal "IN5")
		(30 "In14.Cu" signal "GND6")
		(32 "In15.Cu" signal "IN6")
		(34 "In16.Cu" signal "GND7")
		(2 "B.Cu" signal "BOTTOM")
		(9 "F.Adhes" user "F.Adhesive")
		(11 "B.Adhes" user "B.Adhesive")
		(13 "F.Paste" user "Package Geometry/Pastemask Top")
		(15 "B.Paste" user "Package Geometry/Pastemask Bottom")
		(5 "F.SilkS" user "Ref Des/Silkscreen Top")
		(7 "B.SilkS" user "Ref Des/Silkscreen Bottom")
		(1 "F.Mask" user "Board Geometry/Soldermask Top")
		(3 "B.Mask" user "Board Geometry/Soldermask Bottom")
		(17 "Dwgs.User" user "User.Drawings")
		(19 "Cmts.User" user "User.Comments")
		(21 "Eco1.User" user "User.Eco1")
		(23 "Eco2.User" user "User.Eco2")
		(25 "Edge.Cuts" user "Board Geometry/Outline")
		(27 "Margin" user)
		(31 "F.CrtYd" user "Package Geometry/Place Bound Top")
		(29 "B.CrtYd" user "Package Geometry/Place Bound Bottom")
		(35 "F.Fab" user "Ref Des/Assembly Top")
		(33 "B.Fab" user "Ref Des/Assembly Bottom")
	)
	(footprint ""
		(layer "F.Cu")
		(at 74.845926 -46.4439 180)
		(property "Reference" "U55"
			(at 0.017526 -2.40157 0)
			(unlocked yes)
			(layer "F.SilkS")
			(effects
				(font
					(size 0.7874 0.5842)
					(thickness 0.1524)
				)
			)
		)
		(property "Value" ""
			(at 0 0 180)
			(layer "F.Fab")
			(effects
				(font
					(size 1.27 1.27)
				)
			)
		)
		(duplicate_pad_numbers_are_jumpers no)
		(fp_line
			(start 1.500124 1.500124)
			(end 1.004062 1.500124)
			(stroke
				(width 0.1524)
				(type default)
			)
			(layer "F.SilkS")
		)
		(fp_line
			(start 1.500124 1.004062)
			(end 1.500124 1.500124)
			(stroke
				(width 0.1524)
				(type default)
			)
			(layer "F.SilkS")
		)
		(fp_line
			(start 1.500124 -1.500124)
			(end 1.500124 -1.004062)
			(stroke
				(width 0.1524)
				(type default)
			)
			(layer "F.SilkS")
		)
		(fp_line
			(start 1.004062 -1.500124)
			(end 1.500124 -1.500124)
			(stroke
				(width 0.1524)
				(type default)
			)
			(layer "F.SilkS")
		)
		(fp_line
			(start -1.004062 1.500124)
			(end -1.500124 1.500124)
			(stroke
				(width 0.1524)
				(type default)
			)
			(layer "F.SilkS")
		)
		(fp_line
			(start -1.500124 1.500124)
			(end -1.500124 1.004062)
			(stroke
				(width 0.1524)
				(type default)
			)
			(layer "F.SilkS")
		)
		(fp_line
			(start -1.500124 -1.004062)
			(end -1.500124 -1.500124)
			(stroke
				(width 0.1524)
				(type default)
			)
			(layer "F.SilkS")
		)
		(fp_line
			(start -1.500124 -1.500124)
			(end -1.004062 -1.500124)
			(stroke
				(width 0.1524)
				(type default)
			)
			(layer "F.SilkS")
		)
		(fp_poly
			(pts
				(xy -1.852676 -2.264918) (xy -2.570988 -1.546352) (xy -1.49352 -1.187196)
			)
			(stroke
				(width 0)
				(type default)
			)
			(fill yes)
			(layer "F.SilkS")
		)
		(fp_line
			(start 1.500124 1.500124)
			(end -1.500124 1.500124)
			(stroke
				(width 0.1)
				(type default)
			)
			(layer "F.Fab")
		)
		(fp_line
			(start 1.500124 -1.500124)
			(end 1.500124 1.500124)
			(stroke
				(width 0.1)
				(type default)
			)
			(layer "F.Fab")
		)
		(fp_line
			(start -1.500124 1.500124)
			(end -1.500124 -1.500124)
			(stroke
				(width 0.1)
				(type default)
			)
			(layer "F.Fab")
		)
		(fp_line
			(start -1.500124 -1.500124)
			(end 1.500124 -1.500124)
			(stroke
				(width 0.1)
				(type default)
			)
			(layer "F.Fab")
		)
		(fp_poly
			(pts
				(xy -2.847848 -1.258062) (xy -2.847848 -0.242062) (xy -1.831848 -0.750062)
			)
			(stroke
				(width 0)
				(type default)
			)
			(fill yes)
			(layer "F.Fab")
		)
		(pad "1" smd rect
			(at -1.400048 -0.750062 90)
			(size 0.2286 0.6096)
			(layers "F.Cu" "F.Mask" "F.Paste")
			(net "SSD2_ADC_A1")
		)
		(pad "2" smd rect
			(at -1.400048 -0.249936 90)
			(size 0.2286 0.6096)
			(layers "F.Cu" "F.Mask" "F.Paste")
			(net "SSD2_ADC_A0")
		)
		(pad "3" smd rect
			(at -1.400048 0.249936 90)
			(size 0.2286 0.6096)
			(layers "F.Cu" "F.Mask" "F.Paste")
			(net "SSD2_ADC_ALERT_N")
		)
		(pad "4" smd rect
			(at -1.400048 0.750062 90)
			(size 0.2286 0.6096)
			(layers "F.Cu" "F.Mask" "F.Paste")
			(net "SMB_SSD2_ADC_SDA")
		)
		(pad "5" smd rect
			(at -0.750062 1.400048 180)
			(size 0.2286 0.6096)
			(layers "F.Cu" "F.Mask" "F.Paste")
			(net "SMB_SSD2_ADC_SCL")
		)
		(pad "6" smd rect
			(at -0.249936 1.400048 180)
			(size 0.2286 0.6096)
			(layers "F.Cu" "F.Mask" "F.Paste")
			(net "Net_4621")
		)
		(pad "7" smd rect
			(at 0.249936 1.400048 180)
			(size 0.2286 0.6096)
			(layers "F.Cu" "F.Mask" "F.Paste")
			(net "Net_4622")
		)
		(pad "8" smd rect
			(at 0.750062 1.400048 180)
			(size 0.2286 0.6096)
			(layers "F.Cu" "F.Mask" "F.Paste")
			(net "Net_4623")
		)
		(pad "9" smd rect
			(at 1.400048 0.750062 90)
			(size 0.2286 0.6096)
			(layers "F.Cu" "F.Mask" "F.Paste")
			(net "P3V3_AUX")
		)
		(pad "10" smd rect
			(at 1.400048 0.249936 90)
			(size 0.2286 0.6096)
			(layers "F.Cu" "F.Mask" "F.Paste")
			(net "GND")
		)
		(pad "11" smd rect
			(at 1.400048 -0.249936 90)
			(size 0.2286 0.6096)
			(layers "F.Cu" "F.Mask" "F.Paste")
			(net "P12V_SSD2_R")
		)
		(pad "12" smd rect
			(at 1.400048 -0.750062 90)
			(size 0.2286 0.6096)
			(layers "F.Cu" "F.Mask" "F.Paste")
			(net "P12V_SSD2_VIN_N")
		)
		(pad "13" smd rect
			(at 0.750062 -1.400048 180)
			(size 0.2286 0.6096)
			(layers "F.Cu" "F.Mask" "F.Paste")
			(net "P12V_SSD2_VIN_P")
		)
		(pad "14" smd rect
			(at 0.249936 -1.400048 180)
			(size 0.2286 0.6096)
			(layers "F.Cu" "F.Mask" "F.Paste")
			(net "Net_4624")
		)
		(pad "15" smd rect
			(at -0.249936 -1.400048 180)
			(size 0.2286 0.6096)
			(layers "F.Cu" "F.Mask" "F.Paste")
			(net "Net_4625")
		)
		(pad "16" smd rect
			(at -0.750062 -1.400048 180)
			(size 0.2286 0.6096)
			(layers "F.Cu" "F.Mask" "F.Paste")
			(net "Net_4626")
		)
		(pad "TH" smd rect
			(at 0 0 180)
			(size 1.7018 1.7018)
			(layers "F.Cu" "F.Mask" "F.Paste")
			(net "GND")
		)
		(zone
			(layer "F.Cu")
			(hatch none 0.5)
			(connect_pads
				(clearance 0)
			)
			(min_thickness 0.25)
			(keepout
				(tracks not_allowed)
				(vias allowed)
				(pads allowed)
				(copperpour not_allowed)
				(footprints allowed)
			)
			(placement
				(enabled no)
				(sheetname "")
			)
			(fill
				(thermal_gap 0.5)
				(thermal_bridge_width 0.5)
				(island_removal_mode 0)
			)
			(polygon
				(pts
					(xy 75.890374 -46.4185) (xy 75.890374 -45.399452) (xy 73.801478 -45.399452) (xy 73.801478 -47.488348)
					(xy 75.890374 -47.488348) (xy 75.890374 -46.4439) (xy 75.747626 -46.4439) (xy 75.747626 -47.3456)
					(xy 73.944226 -47.3456) (xy 73.944226 -45.5422) (xy 75.747626 -45.5422) (xy 75.747626 -46.4185)
				)
			)
		)
	)
	(footprint ""
		(layer "F.Cu")
		(at 148.270468 -392.75639 -90)
		(property "Reference" "C4064"
			(at 0 0 270)
			(layer "F.SilkS")
			(hide yes)
			(effects
				(font
					(size 1.27 1.27)
				)
			)
		)
		(property "Value" ""
			(at 0 0 270)
			(layer "F.Fab")
			(effects
				(font
					(size 1.27 1.27)
				)
			)
		)
		(duplicate_pad_numbers_are_jumpers no)
		(fp_line
			(start -0.7874 0.4064)
			(end -0.7874 -0.4064)
			(stroke
				(width 0.1524)
				(type default)
			)
			(layer "F.SilkS")
		)
		(fp_line
			(start 0.7874 0.4064)
			(end -0.7874 0.4064)
			(stroke
				(width 0.1524)
				(type default)
			)
			(layer "F.SilkS")
		)
		(fp_line
			(start -0.7874 -0.4064)
			(end 0.7874 -0.4064)
			(stroke
				(width 0.1524)
				(type default)
			)
			(layer "F.SilkS")
		)
		(fp_line
			(start 0.7874 -0.4064)
			(end 0.7874 0.4064)
			(stroke
				(width 0.1524)
				(type default)
			)
			(layer "F.SilkS")
		)
		(fp_line
			(start -0.67945 0.3048)
			(end -0.67945 -0.305054)
			(stroke
				(width 0.1)
				(type default)
			)
			(layer "F.Fab")
		)
		(fp_line
			(start -0.12065 0.3048)
			(end -0.67945 0.3048)
			(stroke
				(width 0.1)
				(type default)
			)
			(layer "F.Fab")
		)
		(fp_line
			(start 0.120396 0.3048)
			(end 0.120396 0.2794)
			(stroke
				(width 0.1)
				(type default)
			)
			(layer "F.Fab")
		)
		(fp_line
			(start 0.67945 0.3048)
			(end 0.120396 0.3048)
			(stroke
				(width 0.1)
				(type default)
			)
			(layer "F.Fab")
		)
		(fp_line
			(start -0.12065 0.2794)
			(end -0.12065 0.3048)
			(stroke
				(width 0.1)
				(type default)
			)
			(layer "F.Fab")
		)
		(fp_line
			(start 0.120396 0.2794)
			(end -0.12065 0.2794)
			(stroke
				(width 0.1)
				(type default)
			)
			(layer "F.Fab")
		)
		(fp_line
			(start -0.12065 -0.2794)
			(end 0.12065 -0.2794)
			(stroke
				(width 0.1)
				(type default)
			)
			(layer "F.Fab")
		)
		(fp_line
			(start 0.12065 -0.2794)
			(end 0.12065 -0.3048)
			(stroke
				(width 0.1)
				(type default)
			)
			(layer "F.Fab")
		)
		(fp_line
			(start 0.12065 -0.3048)
			(end 0.67945 -0.3048)
			(stroke
				(width 0.1)
				(type default)
			)
			(layer "F.Fab")
		)
		(fp_line
			(start 0.67945 -0.3048)
			(end 0.67945 0.3048)
			(stroke
				(width 0.1)
				(type default)
			)
			(layer "F.Fab")
		)
		(fp_line
			(start -0.67945 -0.305054)
			(end -0.12065 -0.305054)
			(stroke
				(width 0.1)
				(type default)
			)
			(layer "F.Fab")
		)
		(fp_line
			(start -0.12065 -0.305054)
			(end -0.12065 -0.2794)
			(stroke
				(width 0.1)
				(type default)
			)
			(layer "F.Fab")
		)
		(pad "1" smd circle
			(at -0.40005 0 270)
			(size 0 0)
			(layers "F.Cu" "F.Mask" "F.Paste")
			(net "GND")
		)
		(pad "2" smd circle
			(at 0.40005 0 270)
			(size 0 0)
			(layers "F.Cu" "F.Mask" "F.Paste")
			(net "GPU_BASE_STBY_EN")
		)
	)
	(footprint ""
		(layer "F.Cu")
		(at 165.75659 -17.419574 180)
		(property "Reference" "R1663"
			(at 0 0 180)
			(layer "F.SilkS")
			(hide yes)
			(effects
				(font
					(size 1.27 1.27)
				)
			)
		)
		(property "Value" ""
			(at 0 0 180)
			(layer "F.Fab")
			(effects
				(font
					(size 1.27 1.27)
				)
			)
		)
		(duplicate_pad_numbers_are_jumpers no)
		(fp_line
			(start 0.7874 0.4064)
			(end -0.7874 0.4064)
			(stroke
				(width 0.1524)
				(type default)
			)
			(layer "F.SilkS")
		)
		(fp_line
			(start 0.7874 -0.4064)
			(end 0.7874 0.4064)
			(stroke
				(width 0.1524)
				(type default)
			)
			(layer "F.SilkS")
		)
		(fp_line
			(start -0.7874 0.4064)
			(end -0.7874 -0.4064)
			(stroke
				(width 0.1524)
				(type default)
			)
			(layer "F.SilkS")
		)
		(fp_line
			(start -0.7874 -0.4064)
			(end 0.7874 -0.4064)
			(stroke
				(width 0.1524)
				(type default)
			)
			(layer "F.SilkS")
		)
		(fp_line
			(start 0.67945 0.3048)
			(end 0.120396 0.3048)
			(stroke
				(width 0.1)
				(type default)
			)
			(layer "F.Fab")
		)
		(fp_line
			(start 0.67945 -0.3048)
			(end 0.67945 0.3048)
			(stroke
				(width 0.1)
				(type default)
			)
			(layer "F.Fab")
		)
		(fp_line
			(start 0.12065 -0.2794)
			(end 0.12065 -0.3048)
			(stroke
				(width 0.1)
				(type default)
			)
			(layer "F.Fab")
		)
		(fp_line
			(start 0.12065 -0.3048)
			(end 0.67945 -0.3048)
			(stroke
				(width 0.1)
				(type default)
			)
			(layer "F.Fab")
		)
		(fp_line
			(start 0.120396 0.3048)
			(end 0.120396 0.2794)
			(stroke
				(width 0.1)
				(type default)
			)
			(layer "F.Fab")
		)
		(fp_line
			(start 0.120396 0.2794)
			(end -0.12065 0.2794)
			(stroke
				(width 0.1)
				(type default)
			)
			(layer "F.Fab")
		)
		(fp_line
			(start -0.12065 0.3048)
			(end -0.67945 0.3048)
			(stroke
				(width 0.1)
				(type default)
			)
			(layer "F.Fab")
		)
		(fp_line
			(start -0.12065 0.2794)
			(end -0.12065 0.3048)
			(stroke
				(width 0.1)
				(type default)
			)
			(layer "F.Fab")
		)
		(fp_line
			(start -0.12065 -0.2794)
			(end 0.12065 -0.2794)
			(stroke
				(width 0.1)
				(type default)
			)
			(layer "F.Fab")
		)
		(fp_line
			(start -0.12065 -0.305054)
			(end -0.12065 -0.2794)
			(stroke
				(width 0.1)
				(type default)
			)
			(layer "F.Fab")
		)
		(fp_line
			(start -0.67945 0.3048)
			(end -0.67945 -0.305054)
			(stroke
				(width 0.1)
				(type default)
			)
			(layer "F.Fab")
		)
		(fp_line
			(start -0.67945 -0.305054)
			(end -0.12065 -0.305054)
			(stroke
				(width 0.1)
				(type default)
			)
			(layer "F.Fab")
		)
		(pad "1" smd circle
			(at -0.40005 0 180)
			(size 0 0)
			(layers "F.Cu" "F.Mask" "F.Paste")
			(net "P3V3_SSD5")
		)
		(pad "2" smd circle
			(at 0.40005 0 180)
			(size 0 0)
			(layers "F.Cu" "F.Mask" "F.Paste")
			(net "SMB_ISO_SSD5_SCL")
		)
	)
	(footprint ""
		(layer "F.Cu")
		(at 344.061542 -303.698402 90)
		(property "Reference" "PC152"
			(at 0 0 90)
			(layer "F.SilkS")
			(hide yes)
			(effects
				(font
					(size 1.27 1.27)
				)
			)
		)
		(property "Value" ""
			(at 0 0 90)
			(layer "F.Fab")
			(effects
				(font
					(size 1.27 1.27)
				)
			)
		)
		(duplicate_pad_numbers_are_jumpers no)
		(fp_line
			(start -4.53898 -2.150618)
			(end -4.539742 2.152142)
			(stroke
				(width 0.1524)
				(type default)
			)
			(layer "F.SilkS")
		)
		(fp_line
			(start -4.69138 -2.150618)
			(end -4.692396 2.161032)
			(stroke
				(width 0.1524)
				(type default)
			)
			(layer "F.SilkS")
		)
		(fp_line
			(start -4.84378 -2.150618)
			(end -4.53898 -2.150618)
			(stroke
				(width 0.1524)
				(type default)
			)
			(layer "F.SilkS")
		)
		(fp_line
			(start -4.84378 -2.150618)
			(end -4.842256 2.163064)
			(stroke
				(width 0.1524)
				(type default)
			)
			(layer "F.SilkS")
		)
		(fp_line
			(start 4.53898 -2.15011)
			(end 4.53898 2.15011)
			(stroke
				(width 0.1524)
				(type default)
			)
			(layer "F.SilkS")
		)
		(fp_line
			(start -4.53898 -2.15011)
			(end 4.53898 -2.15011)
			(stroke
				(width 0.1524)
				(type default)
			)
			(layer "F.SilkS")
		)
		(fp_line
			(start 4.53898 2.15011)
			(end -4.53898 2.15011)
			(stroke
				(width 0.1524)
				(type default)
			)
			(layer "F.SilkS")
		)
		(fp_line
			(start -4.53898 2.15011)
			(end -4.53898 -2.15011)
			(stroke
				(width 0.1524)
				(type default)
			)
			(layer "F.SilkS")
		)
		(fp_line
			(start -4.83108 2.150364)
			(end -4.447794 2.149348)
			(stroke
				(width 0.1524)
				(type default)
			)
			(layer "F.SilkS")
		)
		(fp_line
			(start 3.64998 -2.15011)
			(end 3.64998 2.15011)
			(stroke
				(width 0.1)
				(type default)
			)
			(layer "F.Fab")
		)
		(fp_line
			(start -3.64998 -2.15011)
			(end 3.64998 -2.15011)
			(stroke
				(width 0.1)
				(type default)
			)
			(layer "F.Fab")
		)
		(fp_line
			(start 3.64998 2.15011)
			(end -3.64998 2.15011)
			(stroke
				(width 0.1)
				(type default)
			)
			(layer "F.Fab")
		)
		(fp_line
			(start -3.64998 2.15011)
			(end -3.64998 -2.15011)
			(stroke
				(width 0.1)
				(type default)
			)
			(layer "F.Fab")
		)
		(fp_text user "-"
			(at 3.525012 2.45491 90)
			(unlocked yes)
			(layer "F.SilkS")
			(effects
				(font
					(size 1.905 1.4224)
					(thickness 0.1524)
				)
				(justify left)
			)
		)
		(fp_text user "+"
			(at -4.823968 2.643378 90)
			(unlocked yes)
			(layer "F.SilkS")
			(effects
				(font
					(size 1.905 1.4224)
					(thickness 0.1524)
				)
				(justify left)
			)
		)
		(fp_text user "+"
			(at -6.214872 -0.337058 90)
			(unlocked yes)
			(layer "F.Fab")
			(effects
				(font
					(size 1.905 1.4224)
					(thickness 0.1524)
				)
				(justify left)
			)
		)
		(fp_text user "-"
			(at 4.313174 -0.094488 90)
			(unlocked yes)
			(layer "F.Fab")
			(effects
				(font
					(size 1.905 1.4224)
					(thickness 0.1524)
				)
				(justify left)
			)
		)
		(pad "1" smd rect
			(at -3.199892 0 90)
			(size 2.413 2.8194)
			(layers "F.Cu" "F.Mask" "F.Paste")
			(net "P0V8_PEX2")
		)
		(pad "2" smd rect
			(at 3.199892 0 90)
			(size 2.413 2.8194)
			(layers "F.Cu" "F.Mask" "F.Paste")
			(net "GND")
		)
	)
	(footprint ""
		(layer "F.Cu")
		(at 33.287716 -301.220632)
		(property "Reference" "C3024"
			(at 0 0 0)
			(layer "F.SilkS")
			(hide yes)
			(effects
				(font
					(size 1.27 1.27)
				)
			)
		)
		(property "Value" ""
			(at 0 0 0)
			(layer "F.Fab")
			(effects
				(font
					(size 1.27 1.27)
				)
			)
		)
		(duplicate_pad_numbers_are_jumpers no)
		(fp_line
			(start -1.2954 -0.5842)
			(end 1.2954 -0.5842)
			(stroke
				(width 0.1524)
				(type default)
			)
			(layer "F.SilkS")
		)
		(fp_line
			(start -1.2954 0.5842)
			(end -1.2954 -0.5842)
			(stroke
				(width 0.1524)
				(type default)
			)
			(layer "F.SilkS")
		)
		(fp_line
			(start 1.2954 -0.5842)
			(end 1.2954 0.5842)
			(stroke
				(width 0.1524)
				(type default)
			)
			(layer "F.SilkS")
		)
		(fp_line
			(start 1.2954 0.5842)
			(end -1.2954 0.5842)
			(stroke
				(width 0.1524)
				(type default)
			)
			(layer "F.SilkS")
		)
		(fp_line
			(start -1.1938 -0.4064)
			(end -0.8636 -0.4064)
			(stroke
				(width 0.1)
				(type default)
			)
			(layer "F.Fab")
		)
		(fp_line
			(start -1.1938 0.4064)
			(end -1.1938 -0.4064)
			(stroke
				(width 0.1)
				(type default)
			)
			(layer "F.Fab")
		)
		(fp_line
			(start -0.8636 -0.4572)
			(end 0.8636 -0.4572)
			(stroke
				(width 0.1)
				(type default)
			)
			(layer "F.Fab")
		)
		(fp_line
			(start -0.8636 -0.4064)
			(end -0.8636 -0.4572)
			(stroke
				(width 0.1)
				(type default)
			)
			(layer "F.Fab")
		)
		(fp_line
			(start -0.8636 0.4064)
			(end -1.1938 0.4064)
			(stroke
				(width 0.1)
				(type default)
			)
			(layer "F.Fab")
		)
		(fp_line
			(start -0.8636 0.4572)
			(end -0.8636 0.4064)
			(stroke
				(width 0.1)
				(type default)
			)
			(layer "F.Fab")
		)
		(fp_line
			(start 0.8636 -0.4572)
			(end 0.8636 -0.4064)
			(stroke
				(width 0.1)
				(type default)
			)
			(layer "F.Fab")
		)
		(fp_line
			(start 0.8636 -0.4064)
			(end 1.1938 -0.4064)
			(stroke
				(width 0.1)
				(type default)
			)
			(layer "F.Fab")
		)
		(fp_line
			(start 0.8636 0.4064)
			(end 0.8636 0.4572)
			(stroke
				(width 0.1)
				(type default)
			)
			(layer "F.Fab")
		)
		(fp_line
			(start 0.8636 0.4572)
			(end -0.8636 0.4572)
			(stroke
				(width 0.1)
				(type default)
			)
			(layer "F.Fab")
		)
		(fp_line
			(start 1.1938 -0.4064)
			(end 1.1938 0.4064)
			(stroke
				(width 0.1)
				(type default)
			)
			(layer "F.Fab")
		)
		(fp_line
			(start 1.1938 0.4064)
			(end 0.8636 0.4064)
			(stroke
				(width 0.1)
				(type default)
			)
			(layer "F.Fab")
		)
		(pad "1" smd rect
			(at -0.7366 0 270)
			(size 0.7112 0.8128)
			(layers "F.Cu" "F.Mask" "F.Paste")
			(net "PCEPLL1_VDDA18_PEX0")
		)
		(pad "2" smd rect
			(at 0.7366 0 270)
			(size 0.7112 0.8128)
			(layers "F.Cu" "F.Mask" "F.Paste")
			(net "GND")
		)
	)
)
